(kicad_pcb
	(version 20260206)
	(generator "pcbnew")
	(generator_version "10.0")
	(general
		(thickness 1.6)
		(legacy_teardrops no)
	)
	(paper "A4")
	(title_block
		(title "03242023_DA0F0TMBIJ0_F0T_Motherboard_J_brd_V01_OCP.brd")
		(comment 1 "Grand Teton / footprints 2954-2960 of 6105")
	)
	(layers
		(0 "F.Cu" signal "TOP")
		(4 "In1.Cu" signal "GND")
		(6 "In2.Cu" signal "IN1")
		(8 "In3.Cu" signal "GND1")
		(10 "In4.Cu" signal "IN2")
		(12 "In5.Cu" signal "GND2")
		(14 "In6.Cu" signal "IN3")
		(16 "In7.Cu" signal "GND3")
		(18 "In8.Cu" signal "VCC")
		(20 "In9.Cu" signal "VCC1")
		(22 "In10.Cu" signal "GND4")
		(24 "In11.Cu" signal "IN4")
		(26 "In12.Cu" signal "GND5")
		(28 "In13.Cu" signal "IN5")
		(30 "In14.Cu" signal "GND6")
		(32 "In15.Cu" signal "IN6")
		(34 "In16.Cu" signal "GND7")
		(2 "B.Cu" signal "BOTTOM")
		(9 "F.Adhes" user "F.Adhesive")
		(11 "B.Adhes" user "B.Adhesive")
		(13 "F.Paste" user "Package Geometry/Pastemask Top")
		(15 "B.Paste" user "Package Geometry/Pastemask Bottom")
		(5 "F.SilkS" user "Ref Des/Silkscreen Top")
		(7 "B.SilkS" user "Ref Des/Silkscreen Bottom")
		(1 "F.Mask" user "Board Geometry/Soldermask Top")
		(3 "B.Mask" user "Board Geometry/Soldermask Bottom")
		(17 "Dwgs.User" user "User.Drawings")
		(19 "Cmts.User" user "User.Comments")
		(21 "Eco1.User" user "User.Eco1")
		(23 "Eco2.User" user "User.Eco2")
		(25 "Edge.Cuts" user "Board Geometry/Outline")
		(27 "Margin" user)
		(31 "F.CrtYd" user "Package Geometry/Place Bound Top")
		(29 "B.CrtYd" user "Package Geometry/Place Bound Bottom")
		(35 "F.Fab" user "Ref Des/Assembly Top")
		(33 "B.Fab" user "Ref Des/Assembly Bottom")
	)
	(footprint ""
		(layer "F.Cu")
		(at 40.960294 -17.623536 90)
		(property "Reference" "C824"
			(at 0 0 90)
			(layer "F.SilkS")
			(hide yes)
			(effects
				(font
					(size 1.27 1.27)
				)
			)
		)
		(property "Value" ""
			(at 0 0 90)
			(layer "F.Fab")
			(effects
				(font
					(size 1.27 1.27)
				)
			)
		)
		(duplicate_pad_numbers_are_jumpers no)
		(fp_line
			(start 0.299974 -0.150114)
			(end 0.299974 0.150114)
			(stroke
				(width 0.1)
				(type default)
			)
			(layer "F.Fab")
		)
		(fp_line
			(start -0.299974 -0.150114)
			(end 0.299974 -0.150114)
			(stroke
				(width 0.1)
				(type default)
			)
			(layer "F.Fab")
		)
		(fp_line
			(start 0.299974 0.150114)
			(end -0.299974 0.150114)
			(stroke
				(width 0.1)
				(type default)
			)
			(layer "F.Fab")
		)
		(fp_line
			(start -0.299974 0.150114)
			(end -0.299974 -0.150114)
			(stroke
				(width 0.1)
				(type default)
			)
			(layer "F.Fab")
		)
		(pad "1" smd rect
			(at -0.2667 0 90)
			(size 0.3048 0.381)
			(layers "F.Cu" "F.Mask" "F.Paste")
			(net "P5E_CPU1_PE1_TX_C_DN<6>")
		)
		(pad "2" smd rect
			(at 0.2667 0 90)
			(size 0.3048 0.381)
			(layers "F.Cu" "F.Mask" "F.Paste")
			(net "P5E_CPU1_PE1_TX_DN<6>")
		)
	)
	(footprint ""
		(layer "F.Cu")
		(at 86.059518 -408.517344 -90)
		(property "Reference" "C684"
			(at 0 0 270)
			(layer "F.SilkS")
			(hide yes)
			(effects
				(font
					(size 1.27 1.27)
				)
			)
		)
		(property "Value" ""
			(at 0 0 270)
			(layer "F.Fab")
			(effects
				(font
					(size 1.27 1.27)
				)
			)
		)
		(duplicate_pad_numbers_are_jumpers no)
		(fp_line
			(start -0.299974 0.150114)
			(end -0.299974 -0.150114)
			(stroke
				(width 0.1)
				(type default)
			)
			(layer "F.Fab")
		)
		(fp_line
			(start 0.299974 0.150114)
			(end -0.299974 0.150114)
			(stroke
				(width 0.1)
				(type default)
			)
			(layer "F.Fab")
		)
		(fp_line
			(start -0.299974 -0.150114)
			(end 0.299974 -0.150114)
			(stroke
				(width 0.1)
				(type default)
			)
			(layer "F.Fab")
		)
		(fp_line
			(start 0.299974 -0.150114)
			(end 0.299974 0.150114)
			(stroke
				(width 0.1)
				(type default)
			)
			(layer "F.Fab")
		)
		(pad "1" smd rect
			(at -0.2667 0 270)
			(size 0.3048 0.381)
			(layers "F.Cu" "F.Mask" "F.Paste")
			(net "P5E_CPU1_PE4_TX_C_DN<12>")
		)
		(pad "2" smd rect
			(at 0.2667 0 270)
			(size 0.3048 0.381)
			(layers "F.Cu" "F.Mask" "F.Paste")
			(net "P5E_CPU1_PE4_TX_DN<12>")
		)
	)
	(footprint ""
		(layer "F.Cu")
		(at 164.251894 -34.164524)
		(property "Reference" "R4449"
			(at 0 0 0)
			(layer "F.SilkS")
			(hide yes)
			(effects
				(font
					(size 1.27 1.27)
				)
			)
		)
		(property "Value" ""
			(at 0 0 0)
			(layer "F.Fab")
			(effects
				(font
					(size 1.27 1.27)
				)
			)
		)
		(duplicate_pad_numbers_are_jumpers no)
		(fp_line
			(start -0.7874 -0.4064)
			(end 0.7874 -0.4064)
			(stroke
				(width 0.1524)
				(type default)
			)
			(layer "F.SilkS")
		)
		(fp_line
			(start -0.7874 0.4064)
			(end -0.7874 -0.4064)
			(stroke
				(width 0.1524)
				(type default)
			)
			(layer "F.SilkS")
		)
		(fp_line
			(start 0.7874 -0.4064)
			(end 0.7874 0.4064)
			(stroke
				(width 0.1524)
				(type default)
			)
			(layer "F.SilkS")
		)
		(fp_line
			(start 0.7874 0.4064)
			(end -0.7874 0.4064)
			(stroke
				(width 0.1524)
				(type default)
			)
			(layer "F.SilkS")
		)
		(fp_line
			(start -0.67945 -0.305054)
			(end -0.12065 -0.305054)
			(stroke
				(width 0.1)
				(type default)
			)
			(layer "F.Fab")
		)
		(fp_line
			(start -0.67945 0.3048)
			(end -0.67945 -0.305054)
			(stroke
				(width 0.1)
				(type default)
			)
			(layer "F.Fab")
		)
		(fp_line
			(start -0.12065 -0.305054)
			(end -0.12065 -0.2794)
			(stroke
				(width 0.1)
				(type default)
			)
			(layer "F.Fab")
		)
		(fp_line
			(start -0.12065 -0.2794)
			(end 0.12065 -0.2794)
			(stroke
				(width 0.1)
				(type default)
			)
			(layer "F.Fab")
		)
		(fp_line
			(start -0.12065 0.2794)
			(end -0.12065 0.3048)
			(stroke
				(width 0.1)
				(type default)
			)
			(layer "F.Fab")
		)
		(fp_line
			(start -0.12065 0.3048)
			(end -0.67945 0.3048)
			(stroke
				(width 0.1)
				(type default)
			)
			(layer "F.Fab")
		)
		(fp_line
			(start 0.120396 0.2794)
			(end -0.12065 0.2794)
			(stroke
				(width 0.1)
				(type default)
			)
			(layer "F.Fab")
		)
		(fp_line
			(start 0.120396 0.3048)
			(end 0.120396 0.2794)
			(stroke
				(width 0.1)
				(type default)
			)
			(layer "F.Fab")
		)
		(fp_line
			(start 0.12065 -0.3048)
			(end 0.67945 -0.3048)
			(stroke
				(width 0.1)
				(type default)
			)
			(layer "F.Fab")
		)
		(fp_line
			(start 0.12065 -0.2794)
			(end 0.12065 -0.3048)
			(stroke
				(width 0.1)
				(type default)
			)
			(layer "F.Fab")
		)
		(fp_line
			(start 0.67945 -0.3048)
			(end 0.67945 0.3048)
			(stroke
				(width 0.1)
				(type default)
			)
			(layer "F.Fab")
		)
		(fp_line
			(start 0.67945 0.3048)
			(end 0.120396 0.3048)
			(stroke
				(width 0.1)
				(type default)
			)
			(layer "F.Fab")
		)
		(pad "1" smd circle
			(at -0.40005 0)
			(size 0 0)
			(layers "F.Cu" "F.Mask" "F.Paste")
			(net "USB_HUB_2_PSELF")
		)
		(pad "2" smd circle
			(at 0.40005 0)
			(size 0 0)
			(layers "F.Cu" "F.Mask" "F.Paste")
			(net "GND")
		)
	)
	(footprint ""
		(layer "F.Cu")
		(at 454.847452 -21.302218 90)
		(property "Reference" "R3799"
			(at 0 0 90)
			(layer "F.SilkS")
			(hide yes)
			(effects
				(font
					(size 1.27 1.27)
				)
			)
		)
		(property "Value" ""
			(at 0 0 90)
			(layer "F.Fab")
			(effects
				(font
					(size 1.27 1.27)
				)
			)
		)
		(duplicate_pad_numbers_are_jumpers no)
		(fp_line
			(start 0.7874 -0.4064)
			(end 0.7874 0.4064)
			(stroke
				(width 0.1524)
				(type default)
			)
			(layer "F.SilkS")
		)
		(fp_line
			(start -0.7874 -0.4064)
			(end 0.7874 -0.4064)
			(stroke
				(width 0.1524)
				(type default)
			)
			(layer "F.SilkS")
		)
		(fp_line
			(start 0.7874 0.4064)
			(end -0.7874 0.4064)
			(stroke
				(width 0.1524)
				(type default)
			)
			(layer "F.SilkS")
		)
		(fp_line
			(start -0.7874 0.4064)
			(end -0.7874 -0.4064)
			(stroke
				(width 0.1524)
				(type default)
			)
			(layer "F.SilkS")
		)
		(fp_line
			(start -0.12065 -0.305054)
			(end -0.12065 -0.2794)
			(stroke
				(width 0.1)
				(type default)
			)
			(layer "F.Fab")
		)
		(fp_line
			(start -0.67945 -0.305054)
			(end -0.12065 -0.305054)
			(stroke
				(width 0.1)
				(type default)
			)
			(layer "F.Fab")
		)
		(fp_line
			(start 0.67945 -0.3048)
			(end 0.67945 0.3048)
			(stroke
				(width 0.1)
				(type default)
			)
			(layer "F.Fab")
		)
		(fp_line
			(start 0.12065 -0.3048)
			(end 0.67945 -0.3048)
			(stroke
				(width 0.1)
				(type default)
			)
			(layer "F.Fab")
		)
		(fp_line
			(start 0.12065 -0.2794)
			(end 0.12065 -0.3048)
			(stroke
				(width 0.1)
				(type default)
			)
			(layer "F.Fab")
		)
		(fp_line
			(start -0.12065 -0.2794)
			(end 0.12065 -0.2794)
			(stroke
				(width 0.1)
				(type default)
			)
			(layer "F.Fab")
		)
		(fp_line
			(start 0.120396 0.2794)
			(end -0.12065 0.2794)
			(stroke
				(width 0.1)
				(type default)
			)
			(layer "F.Fab")
		)
		(fp_line
			(start -0.12065 0.2794)
			(end -0.12065 0.3048)
			(stroke
				(width 0.1)
				(type default)
			)
			(layer "F.Fab")
		)
		(fp_line
			(start 0.67945 0.3048)
			(end 0.120396 0.3048)
			(stroke
				(width 0.1)
				(type default)
			)
			(layer "F.Fab")
		)
		(fp_line
			(start 0.120396 0.3048)
			(end 0.120396 0.2794)
			(stroke
				(width 0.1)
				(type default)
			)
			(layer "F.Fab")
		)
		(fp_line
			(start -0.12065 0.3048)
			(end -0.67945 0.3048)
			(stroke
				(width 0.1)
				(type default)
			)
			(layer "F.Fab")
		)
		(fp_line
			(start -0.67945 0.3048)
			(end -0.67945 -0.305054)
			(stroke
				(width 0.1)
				(type default)
			)
			(layer "F.Fab")
		)
		(pad "1" smd circle
			(at -0.40005 0 90)
			(size 0 0)
			(layers "F.Cu" "F.Mask" "F.Paste")
			(net "P3V3_AUX")
		)
		(pad "2" smd circle
			(at 0.40005 0 90)
			(size 0 0)
			(layers "F.Cu" "F.Mask" "F.Paste")
			(net "P12V_OCP_FAULT_1")
		)
	)
	(footprint ""
		(layer "F.Cu")
		(at 176.17948 -427.446948)
		(property "Reference" "R2926"
			(at 0 0 0)
			(layer "F.SilkS")
			(hide yes)
			(effects
				(font
					(size 1.27 1.27)
				)
			)
		)
		(property "Value" ""
			(at 0 0 0)
			(layer "F.Fab")
			(effects
				(font
					(size 1.27 1.27)
				)
			)
		)
		(duplicate_pad_numbers_are_jumpers no)
		(fp_line
			(start -0.7874 -0.4064)
			(end 0.7874 -0.4064)
			(stroke
				(width 0.1524)
				(type default)
			)
			(layer "F.SilkS")
		)
		(fp_line
			(start -0.7874 0.4064)
			(end -0.7874 -0.4064)
			(stroke
				(width 0.1524)
				(type default)
			)
			(layer "F.SilkS")
		)
		(fp_line
			(start 0.7874 -0.4064)
			(end 0.7874 0.4064)
			(stroke
				(width 0.1524)
				(type default)
			)
			(layer "F.SilkS")
		)
		(fp_line
			(start 0.7874 0.4064)
			(end -0.7874 0.4064)
			(stroke
				(width 0.1524)
				(type default)
			)
			(layer "F.SilkS")
		)
		(fp_line
			(start -0.67945 -0.305054)
			(end -0.12065 -0.305054)
			(stroke
				(width 0.1)
				(type default)
			)
			(layer "F.Fab")
		)
		(fp_line
			(start -0.67945 0.3048)
			(end -0.67945 -0.305054)
			(stroke
				(width 0.1)
				(type default)
			)
			(layer "F.Fab")
		)
		(fp_line
			(start -0.12065 -0.305054)
			(end -0.12065 -0.2794)
			(stroke
				(width 0.1)
				(type default)
			)
			(layer "F.Fab")
		)
		(fp_line
			(start -0.12065 -0.2794)
			(end 0.12065 -0.2794)
			(stroke
				(width 0.1)
				(type default)
			)
			(layer "F.Fab")
		)
		(fp_line
			(start -0.12065 0.2794)
			(end -0.12065 0.3048)
			(stroke
				(width 0.1)
				(type default)
			)
			(layer "F.Fab")
		)
		(fp_line
			(start -0.12065 0.3048)
			(end -0.67945 0.3048)
			(stroke
				(width 0.1)
				(type default)
			)
			(layer "F.Fab")
		)
		(fp_line
			(start 0.120396 0.2794)
			(end -0.12065 0.2794)
			(stroke
				(width 0.1)
				(type default)
			)
			(layer "F.Fab")
		)
		(fp_line
			(start 0.120396 0.3048)
			(end 0.120396 0.2794)
			(stroke
				(width 0.1)
				(type default)
			)
			(layer "F.Fab")
		)
		(fp_line
			(start 0.12065 -0.3048)
			(end 0.67945 -0.3048)
			(stroke
				(width 0.1)
				(type default)
			)
			(layer "F.Fab")
		)
		(fp_line
			(start 0.12065 -0.2794)
			(end 0.12065 -0.3048)
			(stroke
				(width 0.1)
				(type default)
			)
			(layer "F.Fab")
		)
		(fp_line
			(start 0.67945 -0.3048)
			(end 0.67945 0.3048)
			(stroke
				(width 0.1)
				(type default)
			)
			(layer "F.Fab")
		)
		(fp_line
			(start 0.67945 0.3048)
			(end 0.120396 0.3048)
			(stroke
				(width 0.1)
				(type default)
			)
			(layer "F.Fab")
		)
		(pad "1" smd circle
			(at -0.40005 0)
			(size 0 0)
			(layers "F.Cu" "F.Mask" "F.Paste")
			(net "BMC_MONITER_BUF_R")
		)
		(pad "2" smd circle
			(at 0.40005 0)
			(size 0 0)
			(layers "F.Cu" "F.Mask" "F.Paste")
			(net "GND")
		)
	)
	(footprint ""
		(layer "F.Cu")
		(at 152.978612 -31.341568 90)
		(property "Reference" "R4451"
			(at 0 0 90)
			(layer "F.SilkS")
			(hide yes)
			(effects
				(font
					(size 1.27 1.27)
				)
			)
		)
		(property "Value" ""
			(at 0 0 90)
			(layer "F.Fab")
			(effects
				(font
					(size 1.27 1.27)
				)
			)
		)
		(duplicate_pad_numbers_are_jumpers no)
		(fp_line
			(start 0.7874 -0.4064)
			(end 0.7874 0.4064)
			(stroke
				(width 0.1524)
				(type default)
			)
			(layer "F.SilkS")
		)
		(fp_line
			(start -0.7874 -0.4064)
			(end 0.7874 -0.4064)
			(stroke
				(width 0.1524)
				(type default)
			)
			(layer "F.SilkS")
		)
		(fp_line
			(start 0.7874 0.4064)
			(end -0.7874 0.4064)
			(stroke
				(width 0.1524)
				(type default)
			)
			(layer "F.SilkS")
		)
		(fp_line
			(start -0.7874 0.4064)
			(end -0.7874 -0.4064)
			(stroke
				(width 0.1524)
				(type default)
			)
			(layer "F.SilkS")
		)
		(fp_line
			(start -0.12065 -0.305054)
			(end -0.12065 -0.2794)
			(stroke
				(width 0.1)
				(type default)
			)
			(layer "F.Fab")
		)
		(fp_line
			(start -0.67945 -0.305054)
			(end -0.12065 -0.305054)
			(stroke
				(width 0.1)
				(type default)
			)
			(layer "F.Fab")
		)
		(fp_line
			(start 0.67945 -0.3048)
			(end 0.67945 0.3048)
			(stroke
				(width 0.1)
				(type default)
			)
			(layer "F.Fab")
		)
		(fp_line
			(start 0.12065 -0.3048)
			(end 0.67945 -0.3048)
			(stroke
				(width 0.1)
				(type default)
			)
			(layer "F.Fab")
		)
		(fp_line
			(start 0.12065 -0.2794)
			(end 0.12065 -0.3048)
			(stroke
				(width 0.1)
				(type default)
			)
			(layer "F.Fab")
		)
		(fp_line
			(start -0.12065 -0.2794)
			(end 0.12065 -0.2794)
			(stroke
				(width 0.1)
				(type default)
			)
			(layer "F.Fab")
		)
		(fp_line
			(start 0.120396 0.2794)
			(end -0.12065 0.2794)
			(stroke
				(width 0.1)
				(type default)
			)
			(layer "F.Fab")
		)
		(fp_line
			(start -0.12065 0.2794)
			(end -0.12065 0.3048)
			(stroke
				(width 0.1)
				(type default)
			)
			(layer "F.Fab")
		)
		(fp_line
			(start 0.67945 0.3048)
			(end 0.120396 0.3048)
			(stroke
				(width 0.1)
				(type default)
			)
			(layer "F.Fab")
		)
		(fp_line
			(start 0.120396 0.3048)
			(end 0.120396 0.2794)
			(stroke
				(width 0.1)
				(type default)
			)
			(layer "F.Fab")
		)
		(fp_line
			(start -0.12065 0.3048)
			(end -0.67945 0.3048)
			(stroke
				(width 0.1)
				(type default)
			)
			(layer "F.Fab")
		)
		(fp_line
			(start -0.67945 0.3048)
			(end -0.67945 -0.305054)
			(stroke
				(width 0.1)
				(type default)
			)
			(layer "F.Fab")
		)
		(pad "1" smd circle
			(at -0.40005 0 90)
			(size 0 0)
			(layers "F.Cu" "F.Mask" "F.Paste")
			(net "RST_USB_HUB_N")
		)
		(pad "2" smd circle
			(at 0.40005 0 90)
			(size 0 0)
			(layers "F.Cu" "F.Mask" "F.Paste")
			(net "RST_USB_HUB_2_R_N")
		)
	)
	(footprint ""
		(layer "F.Cu")
		(at 198.9963 -131.694428 -90)
		(property "Reference" "R2528"
			(at 0 0 270)
			(layer "F.SilkS")
			(hide yes)
			(effects
				(font
					(size 1.27 1.27)
				)
			)
		)
		(property "Value" ""
			(at 0 0 270)
			(layer "F.Fab")
			(effects
				(font
					(size 1.27 1.27)
				)
			)
		)
		(duplicate_pad_numbers_are_jumpers no)
		(fp_line
			(start -0.7874 0.4064)
			(end -0.7874 -0.4064)
			(stroke
				(width 0.1524)
				(type default)
			)
			(layer "F.SilkS")
		)
		(fp_line
			(start 0.7874 0.4064)
			(end -0.7874 0.4064)
			(stroke
				(width 0.1524)
				(type default)
			)
			(layer "F.SilkS")
		)
		(fp_line
			(start -0.7874 -0.4064)
			(end 0.7874 -0.4064)
			(stroke
				(width 0.1524)
				(type default)
			)
			(layer "F.SilkS")
		)
		(fp_line
			(start 0.7874 -0.4064)
			(end 0.7874 0.4064)
			(stroke
				(width 0.1524)
				(type default)
			)
			(layer "F.SilkS")
		)
		(fp_line
			(start -0.67945 0.3048)
			(end -0.67945 -0.305054)
			(stroke
				(width 0.1)
				(type default)
			)
			(layer "F.Fab")
		)
		(fp_line
			(start -0.12065 0.3048)
			(end -0.67945 0.3048)
			(stroke
				(width 0.1)
				(type default)
			)
			(layer "F.Fab")
		)
		(fp_line
			(start 0.120396 0.3048)
			(end 0.120396 0.2794)
			(stroke
				(width 0.1)
				(type default)
			)
			(layer "F.Fab")
		)
		(fp_line
			(start 0.67945 0.3048)
			(end 0.120396 0.3048)
			(stroke
				(width 0.1)
				(type default)
			)
			(layer "F.Fab")
		)
		(fp_line
			(start -0.12065 0.2794)
			(end -0.12065 0.3048)
			(stroke
				(width 0.1)
				(type default)
			)
			(layer "F.Fab")
		)
		(fp_line
			(start 0.120396 0.2794)
			(end -0.12065 0.2794)
			(stroke
				(width 0.1)
				(type default)
			)
			(layer "F.Fab")
		)
		(fp_line
			(start -0.12065 -0.2794)
			(end 0.12065 -0.2794)
			(stroke
				(width 0.1)
				(type default)
			)
			(layer "F.Fab")
		)
		(fp_line
			(start 0.12065 -0.2794)
			(end 0.12065 -0.3048)
			(stroke
				(width 0.1)
				(type default)
			)
			(layer "F.Fab")
		)
		(fp_line
			(start 0.12065 -0.3048)
			(end 0.67945 -0.3048)
			(stroke
				(width 0.1)
				(type default)
			)
			(layer "F.Fab")
		)
		(fp_line
			(start 0.67945 -0.3048)
			(end 0.67945 0.3048)
			(stroke
				(width 0.1)
				(type default)
			)
			(layer "F.Fab")
		)
		(fp_line
			(start -0.67945 -0.305054)
			(end -0.12065 -0.305054)
			(stroke
				(width 0.1)
				(type default)
			)
			(layer "F.Fab")
		)
		(fp_line
			(start -0.12065 -0.305054)
			(end -0.12065 -0.2794)
			(stroke
				(width 0.1)
				(type default)
			)
			(layer "F.Fab")
		)
		(pad "1" smd circle
			(at -0.40005 0 270)
			(size 0 0)
			(layers "F.Cu" "F.Mask" "F.Paste")
			(net "P12V_AUX")
		)
		(pad "2" smd circle
			(at 0.40005 0 270)
			(size 0 0)
			(layers "F.Cu" "F.Mask" "F.Paste")
			(net "FM_P12V_HSC_EN_N")
		)
	)
)
